# S9S_MB_2U (Grand Teton) — schematic netlist excerpt (pin names and nets, part order shuffled) for the footprints in the layout excerpt that follows; sources: Cadence DE-HDL packaged netlist, KiCad conversion of 03242023_DA0F0TMBIJ0_F0T_Motherboard_J_brd_V01_OCP.brd

R1703  Q_RES  4.7K 5% CHIP  pkg 0402LF  page 194 : A = P1V8_PCH_AUX ; B = SMB_M2_P0_1V8AUX_SCL_R
C832  Q_CAP_DIFFBUS  DIFF BUS_0.22UF 6.3V 20% X6S  pkg C0201  page 175 : \1\ = P5E_CPU1_PE1_TX_C_DN<2> ; \2\ = P5E_CPU1_PE1_TX_DN<2>
C703  Q_CAP_DIFFBUS  DIFF BUS_0.22UF 6.3V 20% X6S  pkg C0201  page 177 : \1\ = P5E_CPU1_PE4_TX_C_DP<3> ; \2\ = P5E_CPU1_PE4_TX_DP<3>

(kicad_pcb
	(version 20260206)
	(generator "pcbnew")
	(generator_version "10.0")
	(general
		(thickness 1.6)
		(legacy_teardrops no)
	)
	(paper "A4")
	(title_block
		(title "03242023_DA0F0TMBIJ0_F0T_Motherboard_J_brd_V01_OCP.brd")
		(comment 1 "Grand Teton / footprints 1805-1807 of 6105")
	)
	(layers
		(0 "F.Cu" signal "TOP")
		(4 "In1.Cu" signal "GND")
		(6 "In2.Cu" signal "IN1")
		(8 "In3.Cu" signal "GND1")
		(10 "In4.Cu" signal "IN2")
		(12 "In5.Cu" signal "GND2")
		(14 "In6.Cu" signal "IN3")
		(16 "In7.Cu" signal "GND3")
		(18 "In8.Cu" signal "VCC")
		(20 "In9.Cu" signal "VCC1")
		(22 "In10.Cu" signal "GND4")
		(24 "In11.Cu" signal "IN4")
		(26 "In12.Cu" signal "GND5")
		(28 "In13.Cu" signal "IN5")
		(30 "In14.Cu" signal "GND6")
		(32 "In15.Cu" signal "IN6")
		(34 "In16.Cu" signal "GND7")
		(2 "B.Cu" signal "BOTTOM")
		(9 "F.Adhes" user "F.Adhesive")
		(11 "B.Adhes" user "B.Adhesive")
		(13 "F.Paste" user "Package Geometry/Pastemask Top")
		(15 "B.Paste" user "Package Geometry/Pastemask Bottom")
		(5 "F.SilkS" user "Ref Des/Silkscreen Top")
		(7 "B.SilkS" user "Ref Des/Silkscreen Bottom")
		(1 "F.Mask" user "Board Geometry/Soldermask Top")
		(3 "B.Mask" user "Board Geometry/Soldermask Bottom")
		(17 "Dwgs.User" user "User.Drawings")
		(19 "Cmts.User" user "User.Comments")
		(21 "Eco1.User" user "User.Eco1")
		(23 "Eco2.User" user "User.Eco2")
		(25 "Edge.Cuts" user "Board Geometry/Outline")
		(27 "Margin" user)
		(31 "F.CrtYd" user "Package Geometry/Place Bound Top")
		(29 "B.CrtYd" user "Package Geometry/Place Bound Bottom")
		(35 "F.Fab" user "Ref Des/Assembly Top")
		(33 "B.Fab" user "Ref Des/Assembly Bottom")
	)
	(footprint ""
		(layer "F.Cu")
		(at 59.404758 -408.517344 -90)
		(property "Reference" "C703"
			(at 0 0 270)
			(layer "F.SilkS")
			(hide yes)
			(effects
				(font
					(size 1.27 1.27)
				)
			)
		)
		(property "Value" ""
			(at 0 0 270)
			(layer "F.Fab")
			(effects
				(font
					(size 1.27 1.27)
				)
			)
		)
		(duplicate_pad_numbers_are_jumpers no)
		(fp_line
			(start -0.299974 0.150114)
			(end -0.299974 -0.150114)
			(stroke
				(width 0.1)
				(type default)
			)
			(layer "F.Fab")
		)
		(fp_line
			(start 0.299974 0.150114)
			(end -0.299974 0.150114)
			(stroke
				(width 0.1)
				(type default)
			)
			(layer "F.Fab")
		)
		(fp_line
			(start -0.299974 -0.150114)
			(end 0.299974 -0.150114)
			(stroke
				(width 0.1)
				(type default)
			)
			(layer "F.Fab")
		)
		(fp_line
			(start 0.299974 -0.150114)
			(end 0.299974 0.150114)
			(stroke
				(width 0.1)
				(type default)
			)
			(layer "F.Fab")
		)
		(pad "1" smd rect
			(at -0.2667 0 270)
			(size 0.3048 0.381)
			(layers "F.Cu" "F.Mask" "F.Paste")
			(net "P5E_CPU1_PE4_TX_C_DP<3>")
		)
		(pad "2" smd rect
			(at 0.2667 0 270)
			(size 0.3048 0.381)
			(layers "F.Cu" "F.Mask" "F.Paste")
			(net "P5E_CPU1_PE4_TX_DP<3>")
		)
	)
	(footprint ""
		(layer "F.Cu")
		(at 52.17033 -17.623536 90)
		(property "Reference" "C832"
			(at 0 0 90)
			(layer "F.SilkS")
			(hide yes)
			(effects
				(font
					(size 1.27 1.27)
				)
			)
		)
		(property "Value" ""
			(at 0 0 90)
			(layer "F.Fab")
			(effects
				(font
					(size 1.27 1.27)
				)
			)
		)
		(duplicate_pad_numbers_are_jumpers no)
		(fp_line
			(start 0.299974 -0.150114)
			(end 0.299974 0.150114)
			(stroke
				(width 0.1)
				(type default)
			)
			(layer "F.Fab")
		)
		(fp_line
			(start -0.299974 -0.150114)
			(end 0.299974 -0.150114)
			(stroke
				(width 0.1)
				(type default)
			)
			(layer "F.Fab")
		)
		(fp_line
			(start 0.299974 0.150114)
			(end -0.299974 0.150114)
			(stroke
				(width 0.1)
				(type default)
			)
			(layer "F.Fab")
		)
		(fp_line
			(start -0.299974 0.150114)
			(end -0.299974 -0.150114)
			(stroke
				(width 0.1)
				(type default)
			)
			(layer "F.Fab")
		)
		(pad "1" smd rect
			(at -0.2667 0 90)
			(size 0.3048 0.381)
			(layers "F.Cu" "F.Mask" "F.Paste")
			(net "P5E_CPU1_PE1_TX_C_DN<2>")
		)
		(pad "2" smd rect
			(at 0.2667 0 90)
			(size 0.3048 0.381)
			(layers "F.Cu" "F.Mask" "F.Paste")
			(net "P5E_CPU1_PE1_TX_DN<2>")
		)
	)
	(footprint ""
		(layer "F.Cu")
		(at 148.13788 -57.241948)
		(property "Reference" "R1703"
			(at 0 0 0)
			(layer "F.SilkS")
			(hide yes)
			(effects
				(font
					(size 1.27 1.27)
				)
			)
		)
		(property "Value" ""
			(at 0 0 0)
			(layer "F.Fab")
			(effects
				(font
					(size 1.27 1.27)
				)
			)
		)
		(duplicate_pad_numbers_are_jumpers no)
		(fp_line
			(start -0.7874 -0.4064)
			(end 0.7874 -0.4064)
			(stroke
				(width 0.1524)
				(type default)
			)
			(layer "F.SilkS")
		)
		(fp_line
			(start -0.7874 0.4064)
			(end -0.7874 -0.4064)
			(stroke
				(width 0.1524)
				(type default)
			)
			(layer "F.SilkS")
		)
		(fp_line
			(start 0.7874 -0.4064)
			(end 0.7874 0.4064)
			(stroke
				(width 0.1524)
				(type default)
			)
			(layer "F.SilkS")
		)
		(fp_line
			(start 0.7874 0.4064)
			(end -0.7874 0.4064)
			(stroke
				(width 0.1524)
				(type default)
			)
			(layer "F.SilkS")
		)
		(fp_line
			(start -0.67945 -0.305054)
			(end -0.12065 -0.305054)
			(stroke
				(width 0.1)
				(type default)
			)
			(layer "F.Fab")
		)
		(fp_line
			(start -0.67945 0.3048)
			(end -0.67945 -0.305054)
			(stroke
				(width 0.1)
				(type default)
			)
			(layer "F.Fab")
		)
		(fp_line
			(start -0.12065 -0.305054)
			(end -0.12065 -0.2794)
			(stroke
				(width 0.1)
				(type default)
			)
			(layer "F.Fab")
		)
		(fp_line
			(start -0.12065 -0.2794)
			(end 0.12065 -0.2794)
			(stroke
				(width 0.1)
				(type default)
			)
			(layer "F.Fab")
		)
		(fp_line
			(start -0.12065 0.2794)
			(end -0.12065 0.3048)
			(stroke
				(width 0.1)
				(type default)
			)
			(layer "F.Fab")
		)
		(fp_line
			(start -0.12065 0.3048)
			(end -0.67945 0.3048)
			(stroke
				(width 0.1)
				(type default)
			)
			(layer "F.Fab")
		)
		(fp_line
			(start 0.120396 0.2794)
			(end -0.12065 0.2794)
			(stroke
				(width 0.1)
				(type default)
			)
			(layer "F.Fab")
		)
		(fp_line
			(start 0.120396 0.3048)
			(end 0.120396 0.2794)
			(stroke
				(width 0.1)
				(type default)
			)
			(layer "F.Fab")
		)
		(fp_line
			(start 0.12065 -0.3048)
			(end 0.67945 -0.3048)
			(stroke
				(width 0.1)
				(type default)
			)
			(layer "F.Fab")
		)
		(fp_line
			(start 0.12065 -0.2794)
			(end 0.12065 -0.3048)
			(stroke
				(width 0.1)
				(type default)
			)
			(layer "F.Fab")
		)
		(fp_line
			(start 0.67945 -0.3048)
			(end 0.67945 0.3048)
			(stroke
				(width 0.1)
				(type default)
			)
			(layer "F.Fab")
		)
		(fp_line
			(start 0.67945 0.3048)
			(end 0.120396 0.3048)
			(stroke
				(width 0.1)
				(type default)
			)
			(layer "F.Fab")
		)
		(pad "1" smd circle
			(at -0.40005 0)
			(size 0 0)
			(layers "F.Cu" "F.Mask" "F.Paste")
			(net "P1V8_PCH_AUX")
		)
		(pad "2" smd circle
			(at 0.40005 0)
			(size 0 0)
			(layers "F.Cu" "F.Mask" "F.Paste")
			(net "SMB_M2_P0_1V8AUX_SCL_R")
		)
	)
)
